# SCM (Grand Teton) — schematic netlist excerpt (pin names and nets, part order shuffled) for the footprints in the layout excerpt that follows; sources: Cadence DE-HDL packaged netlist, KiCad conversion of 12092022_DA0F0TMDCD0_F0T_Management_Board_D_brd_V3_OCP.brd

R158  Q_RES  33.2 1% CHIP  pkg 0402LF  page 13 : A = FM_DBP_CPU_PREQ_GF_R_N ; B = FM_DBP_CPU_PREQ_GF_N
R270  Q_RES  33.2 1% CHIP  pkg 0402LF  page 34 : A = FM_CPU_MSMI_CATERR_LVT3_PLD_N ; B = FM_CPU_MSMI_CATERR_LVT3_N

(kicad_pcb
	(version 20260206)
	(generator "pcbnew")
	(generator_version "10.0")
	(general
		(thickness 1.6)
		(legacy_teardrops no)
	)
	(paper "A4")
	(title_block
		(title "12092022_DA0F0TMDCD0_F0T_Management_Board_D_brd_V3_OCP.brd")
		(comment 1 "Grand Teton / footprints 911-912 of 1440")
	)
	(layers
		(0 "F.Cu" signal "TOP")
		(4 "In1.Cu" signal "GND")
		(6 "In2.Cu" signal "IN1")
		(8 "In3.Cu" signal "GND1")
		(10 "In4.Cu" signal "IN2")
		(12 "In5.Cu" signal "VCC")
		(14 "In6.Cu" signal "VCC1")
		(16 "In7.Cu" signal "IN3")
		(18 "In8.Cu" signal "GND2")
		(20 "In9.Cu" signal "IN4")
		(22 "In10.Cu" signal "GND3")
		(2 "B.Cu" signal "BOTTOM")
		(9 "F.Adhes" user "F.Adhesive")
		(11 "B.Adhes" user "B.Adhesive")
		(13 "F.Paste" user "Package Geometry/Pastemask Top")
		(15 "B.Paste" user "Package Geometry/Pastemask Bottom")
		(5 "F.SilkS" user "Ref Des/Silkscreen Top")
		(7 "B.SilkS" user "Ref Des/Silkscreen Bottom")
		(1 "F.Mask" user "Board Geometry/Soldermask Top")
		(3 "B.Mask" user "Board Geometry/Soldermask Bottom")
		(17 "Dwgs.User" user "User.Drawings")
		(19 "Cmts.User" user "User.Comments")
		(21 "Eco1.User" user "User.Eco1")
		(23 "Eco2.User" user "User.Eco2")
		(25 "Edge.Cuts" user "Board Geometry/Outline")
		(27 "Margin" user)
		(31 "F.CrtYd" user "Package Geometry/Place Bound Top")
		(29 "B.CrtYd" user "Package Geometry/Place Bound Bottom")
		(35 "F.Fab" user "Ref Des/Assembly Top")
		(33 "B.Fab" user "Ref Des/Assembly Bottom")
	)
	(footprint ""
		(layer "B.Cu")
		(at 52.578 -34.6456 -90)
		(property "Reference" "R158"
			(at 0 0 90)
			(layer "B.SilkS")
			(hide yes)
			(effects
				(font
					(size 1.27 1.27)
				)
				(justify mirror)
			)
		)
		(property "Value" ""
			(at 0 0 90)
			(layer "B.Fab")
			(effects
				(font
					(size 1.27 1.27)
				)
				(justify mirror)
			)
		)
		(duplicate_pad_numbers_are_jumpers no)
		(fp_line
			(start -0.7874 0.4064)
			(end 0.7874 0.4064)
			(stroke
				(width 0.1524)
				(type default)
			)
			(layer "B.SilkS")
		)
		(fp_line
			(start 0.7874 0.4064)
			(end 0.7874 -0.4064)
			(stroke
				(width 0.1524)
				(type default)
			)
			(layer "B.SilkS")
		)
		(fp_line
			(start -0.7874 -0.4064)
			(end -0.7874 0.4064)
			(stroke
				(width 0.1524)
				(type default)
			)
			(layer "B.SilkS")
		)
		(fp_line
			(start 0.7874 -0.4064)
			(end -0.7874 -0.4064)
			(stroke
				(width 0.1524)
				(type default)
			)
			(layer "B.SilkS")
		)
		(fp_line
			(start -0.67945 0.3048)
			(end -0.120396 0.3048)
			(stroke
				(width 0.1)
				(type default)
			)
			(layer "B.Fab")
		)
		(fp_line
			(start -0.120396 0.3048)
			(end -0.120396 0.2794)
			(stroke
				(width 0.1)
				(type default)
			)
			(layer "B.Fab")
		)
		(fp_line
			(start 0.12065 0.3048)
			(end 0.67945 0.3048)
			(stroke
				(width 0.1)
				(type default)
			)
			(layer "B.Fab")
		)
		(fp_line
			(start 0.67945 0.3048)
			(end 0.67945 -0.305054)
			(stroke
				(width 0.1)
				(type default)
			)
			(layer "B.Fab")
		)
		(fp_line
			(start -0.120396 0.2794)
			(end 0.12065 0.2794)
			(stroke
				(width 0.1)
				(type default)
			)
			(layer "B.Fab")
		)
		(fp_line
			(start 0.12065 0.2794)
			(end 0.12065 0.3048)
			(stroke
				(width 0.1)
				(type default)
			)
			(layer "B.Fab")
		)
		(fp_line
			(start -0.12065 -0.2794)
			(end -0.12065 -0.3048)
			(stroke
				(width 0.1)
				(type default)
			)
			(layer "B.Fab")
		)
		(fp_line
			(start 0.12065 -0.2794)
			(end -0.12065 -0.2794)
			(stroke
				(width 0.1)
				(type default)
			)
			(layer "B.Fab")
		)
		(fp_line
			(start -0.67945 -0.3048)
			(end -0.67945 0.3048)
			(stroke
				(width 0.1)
				(type default)
			)
			(layer "B.Fab")
		)
		(fp_line
			(start -0.12065 -0.3048)
			(end -0.67945 -0.3048)
			(stroke
				(width 0.1)
				(type default)
			)
			(layer "B.Fab")
		)
		(fp_line
			(start 0.12065 -0.305054)
			(end 0.12065 -0.2794)
			(stroke
				(width 0.1)
				(type default)
			)
			(layer "B.Fab")
		)
		(fp_line
			(start 0.67945 -0.305054)
			(end 0.12065 -0.305054)
			(stroke
				(width 0.1)
				(type default)
			)
			(layer "B.Fab")
		)
		(pad "1" smd circle
			(at 0.40005 0 90)
			(size 0 0)
			(layers "B.Cu" "B.Mask" "B.Paste")
			(net "FM_DBP_CPU_PREQ_GF_R_N")
		)
		(pad "2" smd circle
			(at -0.40005 0 90)
			(size 0 0)
			(layers "B.Cu" "B.Mask" "B.Paste")
			(net "FM_DBP_CPU_PREQ_GF_N")
		)
	)
	(footprint ""
		(layer "B.Cu")
		(at 17.18056 -85.14588)
		(property "Reference" "R270"
			(at 0 0 0)
			(layer "B.SilkS")
			(hide yes)
			(effects
				(font
					(size 1.27 1.27)
				)
				(justify mirror)
			)
		)
		(property "Value" ""
			(at 0 0 0)
			(layer "B.Fab")
			(effects
				(font
					(size 1.27 1.27)
				)
				(justify mirror)
			)
		)
		(duplicate_pad_numbers_are_jumpers no)
		(fp_line
			(start -0.7874 -0.4064)
			(end -0.7874 0.4064)
			(stroke
				(width 0.1524)
				(type default)
			)
			(layer "B.SilkS")
		)
		(fp_line
			(start -0.7874 0.4064)
			(end 0.7874 0.4064)
			(stroke
				(width 0.1524)
				(type default)
			)
			(layer "B.SilkS")
		)
		(fp_line
			(start 0.7874 -0.4064)
			(end -0.7874 -0.4064)
			(stroke
				(width 0.1524)
				(type default)
			)
			(layer "B.SilkS")
		)
		(fp_line
			(start 0.7874 0.4064)
			(end 0.7874 -0.4064)
			(stroke
				(width 0.1524)
				(type default)
			)
			(layer "B.SilkS")
		)
		(fp_line
			(start -0.67945 -0.3048)
			(end -0.67945 0.3048)
			(stroke
				(width 0.1)
				(type default)
			)
			(layer "B.Fab")
		)
		(fp_line
			(start -0.67945 0.3048)
			(end -0.120396 0.3048)
			(stroke
				(width 0.1)
				(type default)
			)
			(layer "B.Fab")
		)
		(fp_line
			(start -0.12065 -0.3048)
			(end -0.67945 -0.3048)
			(stroke
				(width 0.1)
				(type default)
			)
			(layer "B.Fab")
		)
		(fp_line
			(start -0.12065 -0.2794)
			(end -0.12065 -0.3048)
			(stroke
				(width 0.1)
				(type default)
			)
			(layer "B.Fab")
		)
		(fp_line
			(start -0.120396 0.2794)
			(end 0.12065 0.2794)
			(stroke
				(width 0.1)
				(type default)
			)
			(layer "B.Fab")
		)
		(fp_line
			(start -0.120396 0.3048)
			(end -0.120396 0.2794)
			(stroke
				(width 0.1)
				(type default)
			)
			(layer "B.Fab")
		)
		(fp_line
			(start 0.12065 -0.305054)
			(end 0.12065 -0.2794)
			(stroke
				(width 0.1)
				(type default)
			)
			(layer "B.Fab")
		)
		(fp_line
			(start 0.12065 -0.2794)
			(end -0.12065 -0.2794)
			(stroke
				(width 0.1)
				(type default)
			)
			(layer "B.Fab")
		)
		(fp_line
			(start 0.12065 0.2794)
			(end 0.12065 0.3048)
			(stroke
				(width 0.1)
				(type default)
			)
			(layer "B.Fab")
		)
		(fp_line
			(start 0.12065 0.3048)
			(end 0.67945 0.3048)
			(stroke
				(width 0.1)
				(type default)
			)
			(layer "B.Fab")
		)
		(fp_line
			(start 0.67945 -0.305054)
			(end 0.12065 -0.305054)
			(stroke
				(width 0.1)
				(type default)
			)
			(layer "B.Fab")
		)
		(fp_line
			(start 0.67945 0.3048)
			(end 0.67945 -0.305054)
			(stroke
				(width 0.1)
				(type default)
			)
			(layer "B.Fab")
		)
		(pad "1" smd circle
			(at 0.40005 0 180)
			(size 0 0)
			(layers "B.Cu" "B.Mask" "B.Paste")
			(net "FM_CPU_MSMI_CATERR_LVT3_PLD_N")
		)
		(pad "2" smd circle
			(at -0.40005 0 180)
			(size 0 0)
			(layers "B.Cu" "B.Mask" "B.Paste")
			(net "FM_CPU_MSMI_CATERR_LVT3_N")
		)
	)
)
